(kicad_pcb
	(version 20221018)
	(generator pcbnew)
	(general
    (thickness 1.62)
  )
	(paper "A4")
	(title_block
    (title "ECP5 - Datacenter Secure Control Module (DC-SCM)")
    (date "2024-07-01")
    (rev "1.2.1")
		(comment 9 "footprints 217-220 of 506")
	)
	(layers
    (0 "F.Cu" signal)
    (1 "In1.Cu" power)
    (2 "In2.Cu" signal)
    (3 "In3.Cu" power)
    (4 "In4.Cu" power)
    (5 "In5.Cu" signal)
    (6 "In6.Cu" power)
    (31 "B.Cu" signal)
    (32 "B.Adhes" user "B.Adhesive")
    (33 "F.Adhes" user "F.Adhesive")
    (34 "B.Paste" user)
    (35 "F.Paste" user)
    (36 "B.SilkS" user "B.Silkscreen")
    (37 "F.SilkS" user "F.Silkscreen")
    (38 "B.Mask" user)
    (39 "F.Mask" user)
    (40 "Dwgs.User" user "User.Drawings")
    (41 "Cmts.User" user "User.Comments")
    (42 "Eco1.User" user "User.Eco1")
    (43 "Eco2.User" user "User.Eco2")
    (44 "Edge.Cuts" user)
    (45 "Margin" user)
    (46 "B.CrtYd" user "B.Courtyard")
    (47 "F.CrtYd" user "F.Courtyard")
    (48 "B.Fab" user)
    (49 "F.Fab" user)
  )
	(footprint "antmicro-footprints:SOT-23-3" (layer "B.Cu")
    (at 67.25 85.05)
    (property "Author" "Antmicro")
    (property "License" "Apache-2.0")
    (property "MPN" "2N7002")
    (property "Manufacturer" "ON Semiconductor")
    (property "Sheetfile" "power-supply.kicad_sch")
    (property "Sheetname" "Power supply")
    (property "ki_description" "Power MOSFET, N Channel, 60 V, 115 mA, 1.2 ohm, SOT-23, Surface Mount")
    (property "ki_keywords" "SMT, TRANSISTOR, SEMICONDUCTOR, NMOS")
    (attr smd)
    (fp_text reference "Q11" (at 1 -2.4) (layer "B.SilkS")
        (effects (font (size 0.7 0.7) (thickness 0.127)) (justify mirror))
    )
    (fp_text value "2N7002" (at 0.025 -3.25 180) (layer "B.Fab")
        (effects (font (size 1 1) (thickness 0.15)) (justify mirror))
    )
    (fp_text user "${REFERENCE}" (at -0.125 -0.15 180) (layer "B.Fab")
        (effects (font (size 0.25 0.25) (thickness 0.05)) (justify mirror))
    )
    (fp_text user "Author: Antmicro" (at -1.837 -5.3 180) (layer "B.Fab") hide
        (effects (font (size 0.7 0.7) (thickness 0.15)) (justify left bottom mirror))
    )
    (fp_text user "License: Apache-2.0" (at -1.8 -6.8 180) (layer "B.Fab") hide
        (effects (font (size 0.7 0.7) (thickness 0.15)) (justify left bottom mirror))
    )
    (fp_line (start -1.45 1.35) (end -0.85 1.35)
      (stroke (width 0.15) (type solid)) (layer "B.SilkS"))
    (fp_line (start -0.85 1.35) (end -0.7 1.5)
      (stroke (width 0.15) (type solid)) (layer "B.SilkS"))
    (fp_line (start -0.7 -1.5) (end -0.7 -1.35)
      (stroke (width 0.15) (type solid)) (layer "B.SilkS"))
    (fp_line (start 0.7 -1.5) (end -0.7 -1.5)
      (stroke (width 0.15) (type solid)) (layer "B.SilkS"))
    (fp_line (start 0.7 -0.4) (end 0.7 -1.5)
      (stroke (width 0.15) (type solid)) (layer "B.SilkS"))
    (fp_line (start 0.7 0.4) (end 0.7 1.5)
      (stroke (width 0.15) (type solid)) (layer "B.SilkS"))
    (fp_line (start 0.7 1.5) (end -0.7 1.5)
      (stroke (width 0.15) (type solid)) (layer "B.SilkS"))
    (fp_line (start -1.75 -1.4) (end -1.75 -0.5)
      (stroke (width 0.05) (type solid)) (layer "B.CrtYd"))
    (fp_line (start -1.75 -0.5) (end -0.85 -0.5)
      (stroke (width 0.05) (type solid)) (layer "B.CrtYd"))
    (fp_line (start -1.75 0.5) (end -1.75 1.4)
      (stroke (width 0.05) (type solid)) (layer "B.CrtYd"))
    (fp_line (start -0.9 1.4) (end -1.75 1.4)
      (stroke (width 0.05) (type solid)) (layer "B.CrtYd"))
    (fp_line (start -0.9 1.6) (end -0.9 1.4)
      (stroke (width 0.05) (type solid)) (layer "B.CrtYd"))
    (fp_line (start -0.9 1.6) (end 0.825 1.6)
      (stroke (width 0.05) (type solid)) (layer "B.CrtYd"))
    (fp_line (start -0.85 -1.65) (end -0.85 -1.4)
      (stroke (width 0.05) (type solid)) (layer "B.CrtYd"))
    (fp_line (start -0.85 -1.4) (end -1.75 -1.4)
      (stroke (width 0.05) (type solid)) (layer "B.CrtYd"))
    (fp_line (start -0.85 -0.5) (end -0.85 0.5)
      (stroke (width 0.05) (type solid)) (layer "B.CrtYd"))
    (fp_line (start -0.85 0.5) (end -1.75 0.5)
      (stroke (width 0.05) (type solid)) (layer "B.CrtYd"))
    (fp_line (start 0.825 0.45) (end 1.75 0.45)
      (stroke (width 0.05) (type solid)) (layer "B.CrtYd"))
    (fp_line (start 0.825 1.6) (end 0.825 0.45)
      (stroke (width 0.05) (type solid)) (layer "B.CrtYd"))
    (fp_line (start 0.85 -1.65) (end -0.85 -1.65)
      (stroke (width 0.05) (type solid)) (layer "B.CrtYd"))
    (fp_line (start 0.85 -0.45) (end 0.85 -1.65)
      (stroke (width 0.05) (type solid)) (layer "B.CrtYd"))
    (fp_line (start 1.75 -0.45) (end 0.85 -0.45)
      (stroke (width 0.05) (type solid)) (layer "B.CrtYd"))
    (fp_line (start 1.75 0.45) (end 1.75 -0.45)
      (stroke (width 0.05) (type solid)) (layer "B.CrtYd"))
    (fp_line (start -0.712 -1.519) (end 0.688 -1.519)
      (stroke (width 0.15) (type solid)) (layer "B.Fab"))
    (fp_line (start -0.712 1.325) (end -0.712 -1.523)
      (stroke (width 0.15) (type solid)) (layer "B.Fab"))
    (fp_line (start -0.437 1.526) (end -0.712 1.325)
      (stroke (width 0.15) (type solid)) (layer "B.Fab"))
    (fp_line (start -0.437 1.526) (end 0.688 1.526)
      (stroke (width 0.15) (type solid)) (layer "B.Fab"))
    (fp_line (start 0.688 -1.519) (end 0.688 1.52)
      (stroke (width 0.15) (type solid)) (layer "B.Fab"))
    (pad "1" smd roundrect (at -1.1 0.951) (size 1 0.6) (layers "B.Cu" "B.Paste" "B.Mask") (roundrect_rratio 0.15)
      (net 385 "1V0_PG") (pinfunction "G") (pintype "passive"))
    (pad "2" smd roundrect (at -1.1 -0.949) (size 1 0.6) (layers "B.Cu" "B.Paste" "B.Mask") (roundrect_rratio 0.15)
      (net 1 "GND") (pinfunction "S") (pintype "passive"))
    (pad "3" smd roundrect (at 1.1 0.0005) (size 1 0.6) (layers "B.Cu" "B.Paste" "B.Mask") (roundrect_rratio 0.15)
      (net 395 "Net-(Q11-D)") (pinfunction "D") (pintype "passive"))
  )
	(footprint "antmicro-footprints:SOT-23-3" (layer "B.Cu")
    (at 71.2 93.3 180)
    (property "Author" "Antmicro")
    (property "License" "Apache-2.0")
    (property "MPN" "2N7002")
    (property "Manufacturer" "ON Semiconductor")
    (property "Sheetfile" "power-supply.kicad_sch")
    (property "Sheetname" "Power supply")
    (property "ki_description" "Power MOSFET, N Channel, 60 V, 115 mA, 1.2 ohm, SOT-23, Surface Mount")
    (property "ki_keywords" "SMT, TRANSISTOR, SEMICONDUCTOR, NMOS")
    (attr smd)
    (fp_text reference "Q12" (at 0.1 -2.5 180) (layer "B.SilkS")
        (effects (font (size 0.7 0.7) (thickness 0.127)) (justify mirror))
    )
    (fp_text value "2N7002" (at 0.025 -3.25 180) (layer "B.Fab")
        (effects (font (size 1 1) (thickness 0.15)) (justify mirror))
    )
    (fp_text user "License: Apache-2.0" (at -1.8 -6.8) (layer "B.Fab") hide
        (effects (font (size 0.7 0.7) (thickness 0.15)) (justify left bottom mirror))
    )
    (fp_text user "Author: Antmicro" (at -1.837 -5.3) (layer "B.Fab") hide
        (effects (font (size 0.7 0.7) (thickness 0.15)) (justify left bottom mirror))
    )
    (fp_text user "${REFERENCE}" (at -0.125 -0.15 180) (layer "B.Fab")
        (effects (font (size 0.25 0.25) (thickness 0.05)) (justify mirror))
    )
    (fp_line (start -1.45 1.35) (end -0.85 1.35)
      (stroke (width 0.15) (type solid)) (layer "B.SilkS"))
    (fp_line (start -0.85 1.35) (end -0.7 1.5)
      (stroke (width 0.15) (type solid)) (layer "B.SilkS"))
    (fp_line (start -0.7 -1.5) (end -0.7 -1.35)
      (stroke (width 0.15) (type solid)) (layer "B.SilkS"))
    (fp_line (start 0.7 -1.5) (end -0.7 -1.5)
      (stroke (width 0.15) (type solid)) (layer "B.SilkS"))
    (fp_line (start 0.7 -0.4) (end 0.7 -1.5)
      (stroke (width 0.15) (type solid)) (layer "B.SilkS"))
    (fp_line (start 0.7 0.4) (end 0.7 1.5)
      (stroke (width 0.15) (type solid)) (layer "B.SilkS"))
    (fp_line (start 0.7 1.5) (end -0.7 1.5)
      (stroke (width 0.15) (type solid)) (layer "B.SilkS"))
    (fp_line (start -1.75 -1.4) (end -1.75 -0.5)
      (stroke (width 0.05) (type solid)) (layer "B.CrtYd"))
    (fp_line (start -1.75 -0.5) (end -0.85 -0.5)
      (stroke (width 0.05) (type solid)) (layer "B.CrtYd"))
    (fp_line (start -1.75 0.5) (end -1.75 1.4)
      (stroke (width 0.05) (type solid)) (layer "B.CrtYd"))
    (fp_line (start -0.9 1.4) (end -1.75 1.4)
      (stroke (width 0.05) (type solid)) (layer "B.CrtYd"))
    (fp_line (start -0.9 1.6) (end -0.9 1.4)
      (stroke (width 0.05) (type solid)) (layer "B.CrtYd"))
    (fp_line (start -0.9 1.6) (end 0.825 1.6)
      (stroke (width 0.05) (type solid)) (layer "B.CrtYd"))
    (fp_line (start -0.85 -1.65) (end -0.85 -1.4)
      (stroke (width 0.05) (type solid)) (layer "B.CrtYd"))
    (fp_line (start -0.85 -1.4) (end -1.75 -1.4)
      (stroke (width 0.05) (type solid)) (layer "B.CrtYd"))
    (fp_line (start -0.85 -0.5) (end -0.85 0.5)
      (stroke (width 0.05) (type solid)) (layer "B.CrtYd"))
    (fp_line (start -0.85 0.5) (end -1.75 0.5)
      (stroke (width 0.05) (type solid)) (layer "B.CrtYd"))
    (fp_line (start 0.825 0.45) (end 1.75 0.45)
      (stroke (width 0.05) (type solid)) (layer "B.CrtYd"))
    (fp_line (start 0.825 1.6) (end 0.825 0.45)
      (stroke (width 0.05) (type solid)) (layer "B.CrtYd"))
    (fp_line (start 0.85 -1.65) (end -0.85 -1.65)
      (stroke (width 0.05) (type solid)) (layer "B.CrtYd"))
    (fp_line (start 0.85 -0.45) (end 0.85 -1.65)
      (stroke (width 0.05) (type solid)) (layer "B.CrtYd"))
    (fp_line (start 1.75 -0.45) (end 0.85 -0.45)
      (stroke (width 0.05) (type solid)) (layer "B.CrtYd"))
    (fp_line (start 1.75 0.45) (end 1.75 -0.45)
      (stroke (width 0.05) (type solid)) (layer "B.CrtYd"))
    (fp_line (start -0.712 -1.519) (end 0.688 -1.519)
      (stroke (width 0.15) (type solid)) (layer "B.Fab"))
    (fp_line (start -0.712 1.325) (end -0.712 -1.523)
      (stroke (width 0.15) (type solid)) (layer "B.Fab"))
    (fp_line (start -0.437 1.526) (end -0.712 1.325)
      (stroke (width 0.15) (type solid)) (layer "B.Fab"))
    (fp_line (start -0.437 1.526) (end 0.688 1.526)
      (stroke (width 0.15) (type solid)) (layer "B.Fab"))
    (fp_line (start 0.688 -1.519) (end 0.688 1.52)
      (stroke (width 0.15) (type solid)) (layer "B.Fab"))
    (pad "1" smd roundrect (at -1.1 0.951 180) (size 1 0.6) (layers "B.Cu" "B.Paste" "B.Mask") (roundrect_rratio 0.15)
      (net 270 "/Power supply/5V0_PG") (pinfunction "G") (pintype "passive"))
    (pad "2" smd roundrect (at -1.1 -0.949 180) (size 1 0.6) (layers "B.Cu" "B.Paste" "B.Mask") (roundrect_rratio 0.15)
      (net 1 "GND") (pinfunction "S") (pintype "passive"))
    (pad "3" smd roundrect (at 1.1 0.0005 180) (size 1 0.6) (layers "B.Cu" "B.Paste" "B.Mask") (roundrect_rratio 0.15)
      (net 396 "Net-(Q12-D)") (pinfunction "D") (pintype "passive"))
  )
	(footprint "antmicro-footprints:SOT-23-3" (layer "B.Cu")
    (at 67.25 93.25 180)
    (property "Author" "Antmicro")
    (property "License" "Apache-2.0")
    (property "MPN" "2N7002")
    (property "Manufacturer" "ON Semiconductor")
    (property "Sheetfile" "power-supply.kicad_sch")
    (property "Sheetname" "Power supply")
    (property "ki_description" "Power MOSFET, N Channel, 60 V, 115 mA, 1.2 ohm, SOT-23, Surface Mount")
    (property "ki_keywords" "SMT, TRANSISTOR, SEMICONDUCTOR, NMOS")
    (attr smd)
    (fp_text reference "Q13" (at -0.25 -2.55 180) (layer "B.SilkS")
        (effects (font (size 0.7 0.7) (thickness 0.127)) (justify mirror))
    )
    (fp_text value "2N7002" (at 0.025 -3.25 180) (layer "B.Fab")
        (effects (font (size 1 1) (thickness 0.15)) (justify mirror))
    )
    (fp_text user "License: Apache-2.0" (at -1.8 -6.8) (layer "B.Fab") hide
        (effects (font (size 0.7 0.7) (thickness 0.15)) (justify left bottom mirror))
    )
    (fp_text user "Author: Antmicro" (at -1.837 -5.3) (layer "B.Fab") hide
        (effects (font (size 0.7 0.7) (thickness 0.15)) (justify left bottom mirror))
    )
    (fp_text user "${REFERENCE}" (at -0.125 -0.15 180) (layer "B.Fab")
        (effects (font (size 0.25 0.25) (thickness 0.05)) (justify mirror))
    )
    (fp_line (start -1.45 1.35) (end -0.85 1.35)
      (stroke (width 0.15) (type solid)) (layer "B.SilkS"))
    (fp_line (start -0.85 1.35) (end -0.7 1.5)
      (stroke (width 0.15) (type solid)) (layer "B.SilkS"))
    (fp_line (start -0.7 -1.5) (end -0.7 -1.35)
      (stroke (width 0.15) (type solid)) (layer "B.SilkS"))
    (fp_line (start 0.7 -1.5) (end -0.7 -1.5)
      (stroke (width 0.15) (type solid)) (layer "B.SilkS"))
    (fp_line (start 0.7 -0.4) (end 0.7 -1.5)
      (stroke (width 0.15) (type solid)) (layer "B.SilkS"))
    (fp_line (start 0.7 0.4) (end 0.7 1.5)
      (stroke (width 0.15) (type solid)) (layer "B.SilkS"))
    (fp_line (start 0.7 1.5) (end -0.7 1.5)
      (stroke (width 0.15) (type solid)) (layer "B.SilkS"))
    (fp_line (start -1.75 -1.4) (end -1.75 -0.5)
      (stroke (width 0.05) (type solid)) (layer "B.CrtYd"))
    (fp_line (start -1.75 -0.5) (end -0.85 -0.5)
      (stroke (width 0.05) (type solid)) (layer "B.CrtYd"))
    (fp_line (start -1.75 0.5) (end -1.75 1.4)
      (stroke (width 0.05) (type solid)) (layer "B.CrtYd"))
    (fp_line (start -0.9 1.4) (end -1.75 1.4)
      (stroke (width 0.05) (type solid)) (layer "B.CrtYd"))
    (fp_line (start -0.9 1.6) (end -0.9 1.4)
      (stroke (width 0.05) (type solid)) (layer "B.CrtYd"))
    (fp_line (start -0.9 1.6) (end 0.825 1.6)
      (stroke (width 0.05) (type solid)) (layer "B.CrtYd"))
    (fp_line (start -0.85 -1.65) (end -0.85 -1.4)
      (stroke (width 0.05) (type solid)) (layer "B.CrtYd"))
    (fp_line (start -0.85 -1.4) (end -1.75 -1.4)
      (stroke (width 0.05) (type solid)) (layer "B.CrtYd"))
    (fp_line (start -0.85 -0.5) (end -0.85 0.5)
      (stroke (width 0.05) (type solid)) (layer "B.CrtYd"))
    (fp_line (start -0.85 0.5) (end -1.75 0.5)
      (stroke (width 0.05) (type solid)) (layer "B.CrtYd"))
    (fp_line (start 0.825 0.45) (end 1.75 0.45)
      (stroke (width 0.05) (type solid)) (layer "B.CrtYd"))
    (fp_line (start 0.825 1.6) (end 0.825 0.45)
      (stroke (width 0.05) (type solid)) (layer "B.CrtYd"))
    (fp_line (start 0.85 -1.65) (end -0.85 -1.65)
      (stroke (width 0.05) (type solid)) (layer "B.CrtYd"))
    (fp_line (start 0.85 -0.45) (end 0.85 -1.65)
      (stroke (width 0.05) (type solid)) (layer "B.CrtYd"))
    (fp_line (start 1.75 -0.45) (end 0.85 -0.45)
      (stroke (width 0.05) (type solid)) (layer "B.CrtYd"))
    (fp_line (start 1.75 0.45) (end 1.75 -0.45)
      (stroke (width 0.05) (type solid)) (layer "B.CrtYd"))
    (fp_line (start -0.712 -1.519) (end 0.688 -1.519)
      (stroke (width 0.15) (type solid)) (layer "B.Fab"))
    (fp_line (start -0.712 1.325) (end -0.712 -1.523)
      (stroke (width 0.15) (type solid)) (layer "B.Fab"))
    (fp_line (start -0.437 1.526) (end -0.712 1.325)
      (stroke (width 0.15) (type solid)) (layer "B.Fab"))
    (fp_line (start -0.437 1.526) (end 0.688 1.526)
      (stroke (width 0.15) (type solid)) (layer "B.Fab"))
    (fp_line (start 0.688 -1.519) (end 0.688 1.52)
      (stroke (width 0.15) (type solid)) (layer "B.Fab"))
    (pad "1" smd roundrect (at -1.1 0.951 180) (size 1 0.6) (layers "B.Cu" "B.Paste" "B.Mask") (roundrect_rratio 0.15)
      (net 222 "/Power supply/3V3_PG") (pinfunction "G") (pintype "passive"))
    (pad "2" smd roundrect (at -1.1 -0.949 180) (size 1 0.6) (layers "B.Cu" "B.Paste" "B.Mask") (roundrect_rratio 0.15)
      (net 1 "GND") (pinfunction "S") (pintype "passive"))
    (pad "3" smd roundrect (at 1.1 0.0005 180) (size 1 0.6) (layers "B.Cu" "B.Paste" "B.Mask") (roundrect_rratio 0.15)
      (net 397 "Net-(Q13-D)") (pinfunction "D") (pintype "passive"))
  )
	(footprint "antmicro-footprints:SOT-23-3" (layer "B.Cu")
    (at 71.2 89.15 180)
    (property "Author" "Antmicro")
    (property "License" "Apache-2.0")
    (property "MPN" "2N7002")
    (property "Manufacturer" "ON Semiconductor")
    (property "Sheetfile" "power-supply.kicad_sch")
    (property "Sheetname" "Power supply")
    (property "ki_description" "Power MOSFET, N Channel, 60 V, 115 mA, 1.2 ohm, SOT-23, Surface Mount")
    (property "ki_keywords" "SMT, TRANSISTOR, SEMICONDUCTOR, NMOS")
    (attr smd)
    (fp_text reference "Q14" (at -2.4 -0.9 90) (layer "B.SilkS")
        (effects (font (size 0.7 0.7) (thickness 0.127)) (justify mirror))
    )
    (fp_text value "2N7002" (at 0.025 -3.25) (layer "B.Fab")
        (effects (font (size 1 1) (thickness 0.15)) (justify mirror))
    )
    (fp_text user "Author: Antmicro" (at -1.837 -5.3) (layer "B.Fab") hide
        (effects (font (size 0.7 0.7) (thickness 0.15)) (justify left bottom mirror))
    )
    (fp_text user "${REFERENCE}" (at -0.125 -0.15) (layer "B.Fab")
        (effects (font (size 0.25 0.25) (thickness 0.05)) (justify mirror))
    )
    (fp_text user "License: Apache-2.0" (at -1.8 -6.8) (layer "B.Fab") hide
        (effects (font (size 0.7 0.7) (thickness 0.15)) (justify left bottom mirror))
    )
    (fp_line (start -1.45 1.35) (end -0.85 1.35)
      (stroke (width 0.15) (type solid)) (layer "B.SilkS"))
    (fp_line (start -0.85 1.35) (end -0.7 1.5)
      (stroke (width 0.15) (type solid)) (layer "B.SilkS"))
    (fp_line (start -0.7 -1.5) (end -0.7 -1.35)
      (stroke (width 0.15) (type solid)) (layer "B.SilkS"))
    (fp_line (start 0.7 -1.5) (end -0.7 -1.5)
      (stroke (width 0.15) (type solid)) (layer "B.SilkS"))
    (fp_line (start 0.7 -0.4) (end 0.7 -1.5)
      (stroke (width 0.15) (type solid)) (layer "B.SilkS"))
    (fp_line (start 0.7 0.4) (end 0.7 1.5)
      (stroke (width 0.15) (type solid)) (layer "B.SilkS"))
    (fp_line (start 0.7 1.5) (end -0.7 1.5)
      (stroke (width 0.15) (type solid)) (layer "B.SilkS"))
    (fp_line (start -1.75 -1.4) (end -1.75 -0.5)
      (stroke (width 0.05) (type solid)) (layer "B.CrtYd"))
    (fp_line (start -1.75 -0.5) (end -0.85 -0.5)
      (stroke (width 0.05) (type solid)) (layer "B.CrtYd"))
    (fp_line (start -1.75 0.5) (end -1.75 1.4)
      (stroke (width 0.05) (type solid)) (layer "B.CrtYd"))
    (fp_line (start -0.9 1.4) (end -1.75 1.4)
      (stroke (width 0.05) (type solid)) (layer "B.CrtYd"))
    (fp_line (start -0.9 1.6) (end -0.9 1.4)
      (stroke (width 0.05) (type solid)) (layer "B.CrtYd"))
    (fp_line (start -0.9 1.6) (end 0.825 1.6)
      (stroke (width 0.05) (type solid)) (layer "B.CrtYd"))
    (fp_line (start -0.85 -1.65) (end -0.85 -1.4)
      (stroke (width 0.05) (type solid)) (layer "B.CrtYd"))
    (fp_line (start -0.85 -1.4) (end -1.75 -1.4)
      (stroke (width 0.05) (type solid)) (layer "B.CrtYd"))
    (fp_line (start -0.85 -0.5) (end -0.85 0.5)
      (stroke (width 0.05) (type solid)) (layer "B.CrtYd"))
    (fp_line (start -0.85 0.5) (end -1.75 0.5)
      (stroke (width 0.05) (type solid)) (layer "B.CrtYd"))
    (fp_line (start 0.825 0.45) (end 1.75 0.45)
      (stroke (width 0.05) (type solid)) (layer "B.CrtYd"))
    (fp_line (start 0.825 1.6) (end 0.825 0.45)
      (stroke (width 0.05) (type solid)) (layer "B.CrtYd"))
    (fp_line (start 0.85 -1.65) (end -0.85 -1.65)
      (stroke (width 0.05) (type solid)) (layer "B.CrtYd"))
    (fp_line (start 0.85 -0.45) (end 0.85 -1.65)
      (stroke (width 0.05) (type solid)) (layer "B.CrtYd"))
    (fp_line (start 1.75 -0.45) (end 0.85 -0.45)
      (stroke (width 0.05) (type solid)) (layer "B.CrtYd"))
    (fp_line (start 1.75 0.45) (end 1.75 -0.45)
      (stroke (width 0.05) (type solid)) (layer "B.CrtYd"))
    (fp_line (start -0.712 -1.519) (end 0.688 -1.519)
      (stroke (width 0.15) (type solid)) (layer "B.Fab"))
    (fp_line (start -0.712 1.325) (end -0.712 -1.523)
      (stroke (width 0.15) (type solid)) (layer "B.Fab"))
    (fp_line (start -0.437 1.526) (end -0.712 1.325)
      (stroke (width 0.15) (type solid)) (layer "B.Fab"))
    (fp_line (start -0.437 1.526) (end 0.688 1.526)
      (stroke (width 0.15) (type solid)) (layer "B.Fab"))
    (fp_line (start 0.688 -1.519) (end 0.688 1.52)
      (stroke (width 0.15) (type solid)) (layer "B.Fab"))
    (pad "1" smd roundrect (at -1.1 0.951 180) (size 1 0.6) (layers "B.Cu" "B.Paste" "B.Mask") (roundrect_rratio 0.15)
      (net 236 "/Power supply/2V5_PG") (pinfunction "G") (pintype "passive"))
    (pad "2" smd roundrect (at -1.1 -0.949 180) (size 1 0.6) (layers "B.Cu" "B.Paste" "B.Mask") (roundrect_rratio 0.15)
      (net 1 "GND") (pinfunction "S") (pintype "passive"))
    (pad "3" smd roundrect (at 1.1 0.0005 180) (size 1 0.6) (layers "B.Cu" "B.Paste" "B.Mask") (roundrect_rratio 0.15)
      (net 398 "Net-(Q14-D)") (pinfunction "D") (pintype "passive"))
  )
)
